FILE_TYPE = CONNECTIVITY;
{Allegro Design Entry HDL 17.2-2016 S081 (4005846) 1/11/2022}
"PAGE_NUMBER" = 184;
0"NC";
1"P3V3_AUX\g";
2"P1V05_PCH_AUX\g";
3"P3V3_AUX\g";
4"P1V05_PCH_AUX\g";
5"GND\g";
6"GND\g";
7"GND\g";
8"GND\g";
9"GND\g";
10"GND\g";
11"GND\g";
12"GND\g";
13"GND\g";
14"GND\g";
15"GND\g";
16"GND\g";
17"GND\g";
18"GND\g";
19"GND\g";
20"GND\g";
21"FAB_REV_ID2";
22"FAB_REV_ID1";
23"FAB_REV_ID0";
24"FAB_BMC_REV_ID2";
25"FAB_BMC_REV_ID0";
26"FAB_BMC_REV_ID1";
27"FM_BOARD_BMC_SKU_ID0";
28"FM_BOARD_SKU_ID0";
29"FM_BOARD_SKU_ID1";
30"FM_BOARD_SKU_ID2";
31"FM_BOARD_BMC_SKU_ID2";
32"FM_BOARD_BMC_SKU_ID1";
33"FM_BOARD_SKU_ID4";
34"FM_BOARD_SKU_ID3";
35"FM_BOARD_BMC_SKU_ID3";
36"FM_BOARD_BMC_SKU_ID4";
%"Q_RES"
"2","(-1125,2075)","0","pure_quanta","I1";
;
PART_NUMBER"CS21002FB06"
WATTAGE"1/16W"
TOLERANCE"1%"
VALUE"1K"
PACK_TYPE"0402LF"
MATERIAL"CHIP"
$LOCATION"R4581"
CDS_LIB"pure_quanta"
CDS_LOCATION"R4581"
$SEC"1"
CDS_SEC"1";
"A"
$PN"1"36;
"B"
$PN"2"11;
%"UNIVERSAL_GND"
"1","(-950,4175)","0","logical_power","I10";
;
HDL_POWER"GND"
CDS_LIB"logical_power";
"A"14;
%"Q_RES"
"2","(-950,4400)","0","pure_quanta","I11";
;
PART_NUMBER"CS21002FB06"
PACK_TYPE"0402LF"
TOLERANCE"1%"
WATTAGE"1/16W"
VALUE"1K"
MATERIAL"CHIP"
$LOCATION"R2977"
CDS_LIB"pure_quanta"
CDS_LOCATION"R2977"
$SEC"1"
CDS_SEC"1";
"A"
$PN"1"34;
"B"
$PN"2"14;
%"Q_RES"
"2","(-1225,5225)","0","pure_quanta","I12";
;
PART_NUMBER"CS31002FB08"
PACK_TYPE"0402LF"
TOLERANCE"1%"
MATERIAL"EMPTY"
WATTAGE"1/16W"
VALUE"10K"
$LOCATION"R2234"
CDS_LIB"pure_quanta"
CDS_LOCATION"R2234"
$SEC"1"
CDS_SEC"1";
"A"
$PN"1"4;
"B"
$PN"2"33;
%"Q_RES"
"2","(-950,5225)","0","pure_quanta","I13";
;
PART_NUMBER"CS31002FB08"
TOLERANCE"1%"
WATTAGE"1/16W"
MATERIAL"EMPTY"
VALUE"10K"
PACK_TYPE"0402LF"
$LOCATION"R2976"
CDS_LIB"pure_quanta"
CDS_LOCATION"R2976"
$SEC"1"
CDS_SEC"1";
"A"
$PN"1"4;
"B"
$PN"2"34;
%"UNIVERSAL_POWER"
"1","(-1225,5600)","0","logical_power","I14";
;
HDL_POWER"P1V05_PCH_AUX"
CDS_LIB"logical_power";
"A"4;
%"UNIVERSAL_GND"
"1","(-575,1850)","0","logical_power","I15";
;
HDL_POWER"GND"
CDS_LIB"logical_power";
"A"15;
%"Q_RES"
"2","(-575,2075)","0","pure_quanta","I16";
;
PART_NUMBER"CS21002FB06"
TOLERANCE"1%"
PACK_TYPE"0402LF"
MATERIAL"CHIP"
WATTAGE"1/16W"
VALUE"1K"
$LOCATION"R4598"
CDS_LIB"pure_quanta"
CDS_LOCATION"R4598"
$SEC"1"
CDS_SEC"1";
"A"
$PN"1"31;
"B"
$PN"2"15;
%"UNIVERSAL_GND"
"1","(-300,1850)","0","logical_power","I17";
;
HDL_POWER"GND"
CDS_LIB"logical_power";
"A"16;
%"Q_RES"
"2","(-300,2075)","0","pure_quanta","I18";
;
PART_NUMBER"CS21002FB06"
VALUE"1K"
TOLERANCE"1%"
PACK_TYPE"0402LF"
WATTAGE"1/16W"
MATERIAL"CHIP"
$LOCATION"R4583"
CDS_LIB"pure_quanta"
CDS_LOCATION"R4583"
$SEC"1"
CDS_SEC"1";
"A"
$PN"1"32;
"B"
$PN"2"16;
%"UNIVERSAL_GND"
"1","(-25,1850)","0","logical_power","I19";
;
HDL_POWER"GND"
CDS_LIB"logical_power";
"A"17;
%"UNIVERSAL_GND"
"1","(-1125,1850)","0","logical_power","I2";
;
HDL_POWER"GND"
CDS_LIB"logical_power";
"A"11;
%"Q_RES"
"2","(-25,2075)","0","pure_quanta","I20";
;
PART_NUMBER"CS21002FB06"
VALUE"1K"
TOLERANCE"1%"
MATERIAL"CHIP"
WATTAGE"1/16W"
PACK_TYPE"0402LF"
$LOCATION"R4585"
CDS_LIB"pure_quanta"
CDS_LOCATION"R4585"
$SEC"1"
CDS_SEC"1";
"A"
$PN"1"27;
"B"
$PN"2"17;
%"Q_RES"
"2","(-575,2900)","0","pure_quanta","I22";
;
PART_NUMBER"CS31002FB08"
WATTAGE"1/16W"
VALUE"10K"
TOLERANCE"1%"
PACK_TYPE"0402LF"
MATERIAL"EMPTY"
$LOCATION"R4597"
CDS_LIB"pure_quanta"
CDS_LOCATION"R4597"
$SEC"1"
CDS_SEC"1";
"A"
$PN"1"3;
"B"
$PN"2"31;
%"Q_RES"
"2","(-300,2900)","0","pure_quanta","I23";
;
PART_NUMBER"CS31002FB08"
TOLERANCE"1%"
WATTAGE"1/16W"
PACK_TYPE"0402LF"
VALUE"10K"
MATERIAL"EMPTY"
$LOCATION"R4582"
CDS_LIB"pure_quanta"
CDS_LOCATION"R4582"
$SEC"1"
CDS_SEC"1";
"A"
$PN"1"3;
"B"
$PN"2"32;
%"Q_RES"
"2","(-25,2900)","0","pure_quanta","I24";
;
PART_NUMBER"CS31002FB08"
TOLERANCE"1%"
WATTAGE"1/16W"
MATERIAL"EMPTY"
VALUE"10K"
PACK_TYPE"0402LF"
$LOCATION"R4584"
CDS_LIB"pure_quanta"
CDS_LOCATION"R4584"
$SEC"1"
CDS_SEC"1";
"A"
$PN"1"3;
"B"
$PN"2"27;
%"UNIVERSAL_GND"
"1","(-675,4175)","0","logical_power","I25";
;
HDL_POWER"GND"
CDS_LIB"logical_power";
"A"18;
%"Q_RES"
"2","(-675,4400)","0","pure_quanta","I26";
;
PART_NUMBER"CS21002FB06"
WATTAGE"1/16W"
MATERIAL"CHIP"
VALUE"1K"
TOLERANCE"1%"
PACK_TYPE"0402LF"
$LOCATION"R2980"
CDS_LIB"pure_quanta"
CDS_LOCATION"R2980"
$SEC"1"
CDS_SEC"1";
"A"
$PN"1"30;
"B"
$PN"2"18;
%"UNIVERSAL_GND"
"1","(-400,4175)","0","logical_power","I27";
;
HDL_POWER"GND"
CDS_LIB"logical_power";
"A"19;
%"Q_RES"
"2","(-400,4400)","0","pure_quanta","I28";
;
PART_NUMBER"CS21002FB06"
WATTAGE"1/16W"
MATERIAL"CHIP"
PACK_TYPE"0402LF"
VALUE"1K"
TOLERANCE"1%"
$LOCATION"R2241"
CDS_LIB"pure_quanta"
CDS_LOCATION"R2241"
$SEC"1"
CDS_SEC"1";
"A"
$PN"1"29;
"B"
$PN"2"19;
%"UNIVERSAL_GND"
"1","(-125,4175)","0","logical_power","I29";
;
HDL_POWER"GND"
CDS_LIB"logical_power";
"A"20;
%"UNIVERSAL_GND"
"1","(-850,1850)","0","logical_power","I3";
;
HDL_POWER"GND"
CDS_LIB"logical_power";
"A"12;
%"Q_RES"
"2","(-125,4400)","0","pure_quanta","I30";
;
PART_NUMBER"CS21002FB06"
WATTAGE"1/16W"
MATERIAL"CHIP"
VALUE"1K"
TOLERANCE"1%"
PACK_TYPE"0402LF"
$LOCATION"R2243"
CDS_LIB"pure_quanta"
CDS_LOCATION"R2243"
$SEC"1"
CDS_SEC"1";
"A"
$PN"1"28;
"B"
$PN"2"20;
%"Q_RES"
"2","(-850,2075)","0","pure_quanta","I4";
;
PART_NUMBER"CS21002FB06"
PACK_TYPE"0402LF"
MATERIAL"CHIP"
VALUE"1K"
TOLERANCE"1%"
WATTAGE"1/16W"
$LOCATION"R4592"
CDS_LIB"pure_quanta"
CDS_LOCATION"R4592"
$SEC"1"
CDS_SEC"1";
"A"
$PN"1"35;
"B"
$PN"2"12;
%"Q_RES"
"2","(-675,5225)","0","pure_quanta","I48";
;
PART_NUMBER"CS31002FB08"
VALUE"10K"
PACK_TYPE"0402LF"
MATERIAL"EMPTY"
WATTAGE"1/16W"
TOLERANCE"1%"
$LOCATION"R2979"
CDS_LIB"pure_quanta"
CDS_LOCATION"R2979"
$SEC"1"
CDS_SEC"1";
"A"
$PN"1"4;
"B"
$PN"2"30;
%"Q_RES"
"2","(-400,5225)","0","pure_quanta","I49";
;
PART_NUMBER"CS31002FB08"
PACK_TYPE"0402LF"
MATERIAL"EMPTY"
WATTAGE"1/16W"
TOLERANCE"1%"
VALUE"10K"
$LOCATION"R2240"
CDS_LIB"pure_quanta"
CDS_LOCATION"R2240"
$SEC"1"
CDS_SEC"1";
"A"
$PN"1"4;
"B"
$PN"2"29;
%"Q_RES"
"2","(-1125,2900)","0","pure_quanta","I5";
;
PART_NUMBER"CS31002FB08"
MATERIAL"EMPTY"
WATTAGE"1/16W"
PACK_TYPE"0402LF"
TOLERANCE"1%"
VALUE"10K"
$LOCATION"R4580"
CDS_LIB"pure_quanta"
CDS_LOCATION"R4580"
$SEC"1"
CDS_SEC"1";
"A"
$PN"1"3;
"B"
$PN"2"36;
%"Q_RES"
"2","(-125,5225)","0","pure_quanta","I50";
;
PART_NUMBER"CS31002FB08"
VALUE"10K"
MATERIAL"EMPTY"
PACK_TYPE"0402LF"
TOLERANCE"1%"
WATTAGE"1/16W"
$LOCATION"R2242"
CDS_LIB"pure_quanta"
CDS_LOCATION"R2242"
$SEC"1"
CDS_SEC"1";
"A"
$PN"1"4;
"B"
$PN"2"28;
%"UNIVERSAL_GND"
"1","(2150,1800)","0","logical_power","I56";
;
CDS_LIB"logical_power"
HDL_POWER"GND";
"A"5;
%"UNIVERSAL_GND"
"1","(1875,1800)","0","logical_power","I57";
;
CDS_LIB"logical_power"
HDL_POWER"GND";
"A"6;
%"Q_RES"
"2","(1875,2025)","0","pure_quanta","I58";
;
PART_NUMBER"CS21002FB06"
WATTAGE"1/16W"
VALUE"1K"
PACK_TYPE"0402LF"
MATERIAL"EMPTY"
TOLERANCE"1%"
$LOCATION"R4588"
CDS_LIB"pure_quanta"
CDS_LOCATION"R4588"
$SEC"1"
CDS_SEC"1";
"A"
$PN"1"24;
"B"
$PN"2"6;
%"Q_RES"
"2","(2150,2025)","0","pure_quanta","I59";
;
PART_NUMBER"CS21002FB06"
MATERIAL"EMPTY"
TOLERANCE"1%"
PACK_TYPE"0402LF"
WATTAGE"1/16W"
VALUE"1K"
$LOCATION"R4590"
CDS_LIB"pure_quanta"
CDS_LOCATION"R4590"
$SEC"1"
CDS_SEC"1";
"A"
$PN"1"26;
"B"
$PN"2"5;
%"Q_RES"
"2","(-850,2900)","0","pure_quanta","I6";
;
PART_NUMBER"CS31002FB08"
PACK_TYPE"0402LF"
MATERIAL"EMPTY"
WATTAGE"1/16W"
VALUE"10K"
TOLERANCE"1%"
$LOCATION"R4591"
CDS_LIB"pure_quanta"
CDS_LOCATION"R4591"
$SEC"1"
CDS_SEC"1";
"A"
$PN"1"3;
"B"
$PN"2"35;
%"UNIVERSAL_GND"
"1","(2425,1800)","0","logical_power","I60";
;
CDS_LIB"logical_power"
HDL_POWER"GND";
"A"7;
%"Q_RES"
"2","(2425,2025)","0","pure_quanta","I61";
;
PART_NUMBER"CS21002FB06"
PACK_TYPE"0402LF"
WATTAGE"1/16W"
VALUE"1K"
MATERIAL"EMPTY"
TOLERANCE"1%"
$LOCATION"R4596"
CDS_LIB"pure_quanta"
CDS_LOCATION"R4596"
$SEC"1"
CDS_SEC"1";
"A"
$PN"1"25;
"B"
$PN"2"7;
%"Q_RES"
"2","(1875,2675)","0","pure_quanta","I62";
;
PART_NUMBER"CS31002FB08"
WATTAGE"1/16W"
PACK_TYPE"0402LF"
TOLERANCE"1%"
MATERIAL"CHIP"
VALUE"10K"
$LOCATION"R4586"
CDS_LIB"pure_quanta"
CDS_LOCATION"R4586"
$SEC"1"
CDS_SEC"1";
"A"
$PN"1"1;
"B"
$PN"2"24;
%"Q_RES"
"2","(2150,2675)","0","pure_quanta","I63";
;
PART_NUMBER"CS31002FB08"
VALUE"10K"
MATERIAL"CHIP"
PACK_TYPE"0402LF"
TOLERANCE"1%"
WATTAGE"1/16W"
$LOCATION"R4589"
CDS_LIB"pure_quanta"
CDS_LOCATION"R4589"
$SEC"1"
CDS_SEC"1";
"A"
$PN"1"1;
"B"
$PN"2"26;
%"UNIVERSAL_POWER"
"1","(1875,3050)","2","logical_power","I64";
;
HDL_POWER"P3V3_AUX"
CDS_LIB"logical_power";
"A"1;
%"UNIVERSAL_GND"
"1","(1875,4275)","0","logical_power","I65";
;
CDS_LIB"logical_power"
HDL_POWER"GND";
"A"8;
%"UNIVERSAL_GND"
"1","(2150,4275)","0","logical_power","I66";
;
CDS_LIB"logical_power"
HDL_POWER"GND";
"A"9;
%"Q_RES"
"2","(2425,2675)","0","pure_quanta","I67";
;
PART_NUMBER"CS31002FB08"
MATERIAL"CHIP"
TOLERANCE"1%"
VALUE"10K"
WATTAGE"1/16W"
PACK_TYPE"0402LF"
$LOCATION"R4579"
CDS_LIB"pure_quanta"
CDS_LOCATION"R4579"
$SEC"1"
CDS_SEC"1";
"A"
$PN"1"1;
"B"
$PN"2"25;
%"UNIVERSAL_GND"
"1","(2425,4275)","0","logical_power","I68";
;
CDS_LIB"logical_power"
HDL_POWER"GND";
"A"10;
%"Q_RES"
"2","(1875,4500)","0","pure_quanta","I69";
;
PART_NUMBER"CS21002FB06"
VALUE"1K"
MATERIAL"EMPTY"
WATTAGE"1/16W"
TOLERANCE"1%"
PACK_TYPE"0402LF"
$LOCATION"R2973"
CDS_LIB"pure_quanta"
CDS_LOCATION"R2973"
$SEC"1"
CDS_SEC"1";
"A"
$PN"1"21;
"B"
$PN"2"8;
%"UNIVERSAL_POWER"
"1","(-1125,3275)","2","logical_power","I7";
;
HDL_POWER"P3V3_AUX"
CDS_LIB"logical_power";
"A"3;
%"Q_RES"
"2","(2150,4500)","0","pure_quanta","I70";
;
PART_NUMBER"CS21002FB06"
PACK_TYPE"0402LF"
MATERIAL"EMPTY"
VALUE"1K"
TOLERANCE"1%"
WATTAGE"1/16W"
$LOCATION"R2975"
CDS_LIB"pure_quanta"
CDS_LOCATION"R2975"
$SEC"1"
CDS_SEC"1";
"A"
$PN"1"22;
"B"
$PN"2"9;
%"Q_RES"
"2","(1875,5150)","0","pure_quanta","I71";
;
PART_NUMBER"CS31002FB08"
PACK_TYPE"0402LF"
MATERIAL"CHIP"
WATTAGE"1/16W"
TOLERANCE"1%"
VALUE"10K"
$LOCATION"R2972"
CDS_LIB"pure_quanta"
CDS_LOCATION"R2972"
$SEC"1"
CDS_SEC"1";
"A"
$PN"1"2;
"B"
$PN"2"21;
%"Q_RES"
"2","(2150,5150)","0","pure_quanta","I72";
;
PART_NUMBER"CS31002FB08"
PACK_TYPE"0402LF"
VALUE"10K"
TOLERANCE"1%"
WATTAGE"1/16W"
MATERIAL"CHIP"
$LOCATION"R2974"
CDS_LIB"pure_quanta"
CDS_LOCATION"R2974"
$SEC"1"
CDS_SEC"1";
"A"
$PN"1"2;
"B"
$PN"2"22;
%"UNIVERSAL_POWER"
"1","(1875,5525)","0","logical_power","I73";
;
HDL_POWER"P1V05_PCH_AUX"
CDS_LIB"logical_power";
"A"2;
%"Q_RES"
"2","(2425,4500)","0","pure_quanta","I74";
;
PART_NUMBER"CS21002FB06"
WATTAGE"1/16W"
VALUE"1K"
TOLERANCE"1%"
MATERIAL"EMPTY"
PACK_TYPE"0402LF"
$LOCATION"R2978"
CDS_LIB"pure_quanta"
CDS_LOCATION"R2978"
$SEC"1"
CDS_SEC"1";
"A"
$PN"1"23;
"B"
$PN"2"10;
%"Q_RES"
"2","(2425,5150)","0","pure_quanta","I75";
;
PART_NUMBER"CS31002FB08"
PACK_TYPE"0402LF"
TOLERANCE"1%"
VALUE"10K"
WATTAGE"1/16W"
MATERIAL"CHIP"
$LOCATION"R2232"
CDS_LIB"pure_quanta"
CDS_LOCATION"R2232"
$SEC"1"
CDS_SEC"1";
"A"
$PN"1"2;
"B"
$PN"2"23;
%"UNIVERSAL_GND"
"1","(-1225,4175)","0","logical_power","I8";
;
HDL_POWER"GND"
CDS_LIB"logical_power";
"A"13;
%"Q_RES"
"2","(-1225,4400)","0","pure_quanta","I9";
;
PART_NUMBER"CS21002FB06"
PACK_TYPE"0402LF"
MATERIAL"CHIP"
WATTAGE"1/16W"
TOLERANCE"1%"
VALUE"1K"
$LOCATION"R2235"
CDS_LIB"pure_quanta"
CDS_LOCATION"R2235"
$SEC"1"
CDS_SEC"1";
"A"
$PN"1"33;
"B"
$PN"2"13;
END.
